(kicad_pcb
	(version 20260206)
	(generator "pcbnew")
	(generator_version "10.0")
	(general
		(thickness 1.6)
		(legacy_teardrops no)
	)
	(paper "A4")
	(title_block
		(title "v1-chassis-manager — T6M_CM_d_v01_1031_1645.brd")
		(comment 1 "Open CloudServer (Microsoft) / footprints 583-588 of 2512")
	)
	(layers
		(0 "F.Cu" signal "TOP")
		(4 "In1.Cu" signal "GND1")
		(6 "In2.Cu" signal "IN1")
		(8 "In3.Cu" signal "VCC1")
		(10 "In4.Cu" signal "VCC2")
		(12 "In5.Cu" signal "GND2")
		(14 "In6.Cu" signal "IN2")
		(16 "In7.Cu" signal "IN3")
		(18 "In8.Cu" signal "GND3")
		(2 "B.Cu" signal "BOTTOM")
		(9 "F.Adhes" user "F.Adhesive")
		(11 "B.Adhes" user "B.Adhesive")
		(13 "F.Paste" user "Package Geometry/Pastemask Top")
		(15 "B.Paste" user "Package Geometry/Pastemask Bottom")
		(5 "F.SilkS" user "Ref Des/Silkscreen Top")
		(7 "B.SilkS" user "Ref Des/Silkscreen Bottom")
		(1 "F.Mask" user "Board Geometry/Soldermask Top")
		(3 "B.Mask" user "Board Geometry/Soldermask Bottom")
		(17 "Dwgs.User" user "User.Drawings")
		(19 "Cmts.User" user "User.Comments")
		(21 "Eco1.User" user "User.Eco1")
		(23 "Eco2.User" user "User.Eco2")
		(25 "Edge.Cuts" user "Board Geometry/Outline")
		(27 "Margin" user)
		(31 "F.CrtYd" user "Package Geometry/Place Bound Top")
		(29 "B.CrtYd" user "Package Geometry/Place Bound Bottom")
		(35 "F.Fab" user "Ref Des/Assembly Top")
		(33 "B.Fab" user "Ref Des/Assembly Bottom")
	)
	(footprint ""
		(layer "F.Cu")
		(at 70.035166 -111.801148 -90)
		(property "Reference" "Q37"
			(at 1.470914 -1.372616 90)
			(unlocked yes)
			(layer "F.SilkS")
			(effects
				(font
					(size 0.7874 0.5842)
					(thickness 0.1524)
				)
			)
		)
		(property "Value" ""
			(at 0 0 270)
			(layer "F.Fab")
			(effects
				(font
					(size 1.27 1.27)
				)
			)
		)
		(duplicate_pad_numbers_are_jumpers no)
		(fp_line
			(start -0.100076 2.474976)
			(end -0.100076 2.295906)
			(stroke
				(width 0.1524)
				(type default)
			)
			(layer "F.SilkS")
		)
		(fp_line
			(start 1.044448 2.474976)
			(end -0.100076 2.474976)
			(stroke
				(width 0.1524)
				(type default)
			)
			(layer "F.SilkS")
		)
		(fp_line
			(start 2.899918 2.474976)
			(end 1.755648 2.474976)
			(stroke
				(width 0.1524)
				(type default)
			)
			(layer "F.SilkS")
		)
		(fp_line
			(start 2.899918 2.295906)
			(end 2.899918 2.474976)
			(stroke
				(width 0.1524)
				(type default)
			)
			(layer "F.SilkS")
		)
		(fp_line
			(start -0.100076 -0.320294)
			(end -0.100076 -0.525018)
			(stroke
				(width 0.1524)
				(type default)
			)
			(layer "F.SilkS")
		)
		(fp_line
			(start -0.100076 -0.525018)
			(end 1.044448 -0.525018)
			(stroke
				(width 0.1524)
				(type default)
			)
			(layer "F.SilkS")
		)
		(fp_line
			(start 1.755648 -0.525018)
			(end 2.899918 -0.525018)
			(stroke
				(width 0.1524)
				(type default)
			)
			(layer "F.SilkS")
		)
		(fp_line
			(start 2.899918 -0.525018)
			(end 2.899918 -0.345694)
			(stroke
				(width 0.1524)
				(type default)
			)
			(layer "F.SilkS")
		)
		(fp_poly
			(pts
				(xy -0.25527 -1.65481) (xy 0.263652 -1.65481) (xy 0 -1.077468)
			)
			(stroke
				(width 0)
				(type default)
			)
			(fill yes)
			(layer "F.SilkS")
		)
		(fp_poly
			(pts
				(xy -0.100076 -0.525018) (xy -0.100076 -0.244094) (xy -0.301752 -0.244094) (xy -0.301752 2.194306)
				(xy -0.100076 2.194306) (xy -0.100076 2.474976) (xy 1.120648 2.474976) (xy 1.120648 2.651506) (xy 1.679448 2.651506)
				(xy 1.679448 2.474976) (xy 2.899918 2.474976) (xy 2.899918 2.219706) (xy 3.101848 2.219706) (xy 3.101848 -0.269494)
				(xy 2.899918 -0.269494) (xy 2.899918 -0.525018) (xy 1.679448 -0.525018) (xy 1.679448 -0.701294)
				(xy 1.120648 -0.701294) (xy 1.120648 -0.525018)
			)
			(stroke
				(width 0)
				(type default)
			)
			(fill no)
			(layer "F.CrtYd")
		)
		(fp_line
			(start -0.100076 2.474976)
			(end -0.100076 -0.525018)
			(stroke
				(width 0.1)
				(type default)
			)
			(layer "F.Fab")
		)
		(fp_line
			(start 2.899918 2.474976)
			(end -0.100076 2.474976)
			(stroke
				(width 0.1)
				(type default)
			)
			(layer "F.Fab")
		)
		(fp_line
			(start -0.100076 -0.525018)
			(end 2.899918 -0.525018)
			(stroke
				(width 0.1)
				(type default)
			)
			(layer "F.Fab")
		)
		(fp_line
			(start 2.899918 -0.525018)
			(end 2.899918 2.474976)
			(stroke
				(width 0.1)
				(type default)
			)
			(layer "F.Fab")
		)
		(pad "1" smd rect
			(at 0 0 180)
			(size 0.3556 0.508)
			(layers "F.Cu" "F.Mask" "F.Paste")
			(net "P1V8_NODE1")
		)
		(pad "2" smd rect
			(at 0 0.649986 180)
			(size 0.3556 0.508)
			(layers "F.Cu" "F.Mask" "F.Paste")
			(net "P1V8_NODE1")
		)
		(pad "3" smd rect
			(at 0 1.299972 180)
			(size 0.3556 0.508)
			(layers "F.Cu" "F.Mask" "F.Paste")
			(net "P1V8_NODE1")
		)
		(pad "4" smd rect
			(at 0 1.949958 180)
			(size 0.3556 0.508)
			(layers "F.Cu" "F.Mask" "F.Paste")
			(net "FM_CPLD_NODE1_P1V8_EN_LV")
		)
		(pad "5" smd custom
			(at 1.400048 0.975106 180)
			(size 0.569976 0.569976)
			(layers "F.Cu" "F.Mask" "F.Paste")
			(net "P1V8_STB_NODE1")
			(options
				(clearance outline)
				(anchor circle)
			)
			(primitives
				(gr_poly
					(pts
						(xy -1.225042 1.139952) (xy -1.225042 0.724916) (xy -1.605026 0.724916) (xy -1.605026 0.295148)
						(xy -1.225042 0.295148) (xy -1.225042 -0.839978) (xy -1.175004 -0.839978) (xy -1.175004 -1.139952)
						(xy -0.774954 -1.139952) (xy -0.774954 -0.839978) (xy -0.525018 -0.839978) (xy -0.525018 -1.139952)
						(xy -0.124968 -1.139952) (xy -0.124968 -0.839978) (xy 0.124968 -0.839978) (xy 0.124968 -1.139952)
						(xy 0.525018 -1.139952) (xy 0.525018 -0.839978) (xy 0.774954 -0.839978) (xy 0.774954 -1.139952)
						(xy 1.175004 -1.139952) (xy 1.175004 -0.839978) (xy 1.225042 -0.839978) (xy 1.225042 0.295148)
						(xy 1.605026 0.295148) (xy 1.605026 0.724916) (xy 1.225042 0.724916) (xy 1.225042 1.139952)
					)
					(width 0)
					(fill yes)
				)
			)
		)
		(zone
			(layer "F.Cu")
			(hatch none 0.5)
			(connect_pads
				(clearance 0)
			)
			(min_thickness 0.25)
			(keepout
				(tracks not_allowed)
				(vias allowed)
				(pads allowed)
				(copperpour not_allowed)
				(footprints allowed)
			)
			(placement
				(enabled no)
				(sheetname "")
			)
			(fill
				(thermal_gap 0.5)
				(thermal_bridge_width 0.5)
				(island_removal_mode 0)
			)
			(polygon
				(pts
					(xy 70.55866 -111.4679) (xy 67.56146 -111.4679) (xy 67.56146 -111.0869) (xy 70.55866 -111.0869)
				)
			)
		)
		(zone
			(layer "F.Cu")
			(hatch none 0.5)
			(connect_pads
				(clearance 0)
			)
			(min_thickness 0.25)
			(keepout
				(tracks allowed)
				(vias not_allowed)
				(pads allowed)
				(copperpour not_allowed)
				(footprints allowed)
			)
			(placement
				(enabled no)
				(sheetname "")
			)
			(fill
				(thermal_gap 0.5)
				(thermal_bridge_width 0.5)
				(island_removal_mode 0)
			)
			(polygon
				(pts
					(xy 70.55866 -111.0869) (xy 67.56146 -111.0869) (xy 67.56146 -111.4679) (xy 70.55866 -111.4679)
				)
			)
		)
	)
	(footprint ""
		(layer "F.Cu")
		(at 8.722614 -4.27228)
		(property "Reference" "U10"
			(at -3.361436 1.02743 90)
			(unlocked yes)
			(layer "F.SilkS")
			(effects
				(font
					(size 0.7874 0.5842)
					(thickness 0.1524)
				)
			)
		)
		(property "Value" ""
			(at 0 0 0)
			(layer "F.Fab")
			(effects
				(font
					(size 1.27 1.27)
				)
			)
		)
		(duplicate_pad_numbers_are_jumpers no)
		(fp_line
			(start -1.1176 -1.7272)
			(end -1.1176 -0.254)
			(stroke
				(width 0.1524)
				(type default)
			)
			(layer "F.SilkS")
		)
		(fp_line
			(start -1.1176 -1.7272)
			(end 1.1176 -1.7272)
			(stroke
				(width 0.1524)
				(type default)
			)
			(layer "F.SilkS")
		)
		(fp_line
			(start -1.1176 -0.254)
			(end -0.7366 0)
			(stroke
				(width 0.1524)
				(type default)
			)
			(layer "F.SilkS")
		)
		(fp_line
			(start -1.1176 0.254)
			(end -1.1176 1.7272)
			(stroke
				(width 0.1524)
				(type default)
			)
			(layer "F.SilkS")
		)
		(fp_line
			(start -0.7366 0)
			(end -1.1176 0.254)
			(stroke
				(width 0.1524)
				(type default)
			)
			(layer "F.SilkS")
		)
		(fp_line
			(start 1.1176 -1.7272)
			(end 1.1176 1.7272)
			(stroke
				(width 0.1524)
				(type default)
			)
			(layer "F.SilkS")
		)
		(fp_line
			(start 1.1176 1.7272)
			(end -1.1176 1.7272)
			(stroke
				(width 0.1524)
				(type default)
			)
			(layer "F.SilkS")
		)
		(fp_rect
			(start -1.1176 1.5748)
			(end 1.1176 -1.5748)
			(stroke
				(width 0)
				(type default)
			)
			(fill no)
			(layer "F.CrtYd")
		)
		(pad "1" smd rect
			(at -0.649986 0.999998)
			(size 0.3556 1.1176)
			(layers "F.Cu" "F.Mask" "F.Paste")
			(net "P3V3_STB_NODE1")
		)
		(pad "2" smd rect
			(at 0 0.999998)
			(size 0.3556 1.1176)
			(layers "F.Cu" "F.Mask" "F.Paste")
			(net "GND")
		)
		(pad "3" smd rect
			(at 0.649986 0.999998)
			(size 0.3556 1.1176)
			(layers "F.Cu" "F.Mask" "F.Paste")
			(net "SMB_MUX_CPU_ICS_NODE1_CLK")
		)
		(pad "4" smd rect
			(at 0.649986 -0.999998)
			(size 0.3556 1.1176)
			(layers "F.Cu" "F.Mask" "F.Paste")
			(net "SMB_MUX_CPU_ICS_NODE1_DAT")
		)
		(pad "5" smd rect
			(at 0 -0.999998)
			(size 0.3556 1.1176)
			(layers "F.Cu" "F.Mask" "F.Paste")
			(net "PV_VDDR_NODE1_VREF_RW")
		)
		(pad "6" smd rect
			(at -0.649986 -0.999998)
			(size 0.3556 1.1176)
			(layers "F.Cu" "F.Mask" "F.Paste")
			(net "PV_VDDR_NODE1")
		)
	)
	(footprint ""
		(layer "F.Cu")
		(at 15.808452 -48.052228)
		(property "Reference" "R788"
			(at 12.177268 4.144518 0)
			(unlocked yes)
			(layer "F.SilkS")
			(effects
				(font
					(size 0.7874 0.5842)
					(thickness 0.1524)
				)
				(justify left)
			)
		)
		(property "Value" ""
			(at 0 0 0)
			(layer "F.Fab")
			(effects
				(font
					(size 1.27 1.27)
				)
			)
		)
		(duplicate_pad_numbers_are_jumpers no)
		(fp_line
			(start -0.7874 -0.4064)
			(end 0.7874 -0.4064)
			(stroke
				(width 0.1524)
				(type default)
			)
			(layer "F.SilkS")
		)
		(fp_line
			(start -0.7874 0.4064)
			(end -0.7874 -0.4064)
			(stroke
				(width 0.1524)
				(type default)
			)
			(layer "F.SilkS")
		)
		(fp_line
			(start 0.7874 -0.4064)
			(end 0.7874 0.4064)
			(stroke
				(width 0.1524)
				(type default)
			)
			(layer "F.SilkS")
		)
		(fp_line
			(start 0.7874 0.4064)
			(end -0.7874 0.4064)
			(stroke
				(width 0.1524)
				(type default)
			)
			(layer "F.SilkS")
		)
		(fp_poly
			(pts
				(xy -0.508 0.2794) (xy -0.508 0.2286) (xy -0.635 0.2286) (xy -0.635 -0.254) (xy -0.5334 -0.254)
				(xy -0.5334 -0.2794) (xy 0.5334 -0.2794) (xy 0.5334 -0.254) (xy 0.635 -0.254) (xy 0.635 0.254) (xy 0.5334 0.254)
				(xy 0.5334 0.2794)
			)
			(stroke
				(width 0)
				(type default)
			)
			(fill no)
			(layer "F.CrtYd")
		)
		(pad "1" smd rect
			(at 0.40005 0)
			(size 0.4572 0.508)
			(layers "F.Cu" "F.Mask" "F.Paste")
			(net "CRT_G_L")
		)
		(pad "2" smd rect
			(at -0.40005 0)
			(size 0.4572 0.508)
			(layers "F.Cu" "F.Mask" "F.Paste")
			(net "CRT_G")
		)
	)
	(footprint ""
		(layer "F.Cu")
		(at 16.499332 -134.725918)
		(property "Reference" "PR27"
			(at -0.802894 -2.192274 0)
			(unlocked yes)
			(layer "F.SilkS")
			(effects
				(font
					(size 0.7874 0.5842)
					(thickness 0.1524)
				)
				(justify left)
			)
		)
		(property "Value" ""
			(at 0 0 0)
			(layer "F.Fab")
			(effects
				(font
					(size 1.27 1.27)
				)
			)
		)
		(duplicate_pad_numbers_are_jumpers no)
		(fp_line
			(start -0.7874 -0.4064)
			(end 0.7874 -0.4064)
			(stroke
				(width 0.1524)
				(type default)
			)
			(layer "F.SilkS")
		)
		(fp_line
			(start -0.7874 0.4064)
			(end -0.7874 -0.4064)
			(stroke
				(width 0.1524)
				(type default)
			)
			(layer "F.SilkS")
		)
		(fp_line
			(start 0.7874 -0.4064)
			(end 0.7874 0.4064)
			(stroke
				(width 0.1524)
				(type default)
			)
			(layer "F.SilkS")
		)
		(fp_line
			(start 0.7874 0.4064)
			(end -0.7874 0.4064)
			(stroke
				(width 0.1524)
				(type default)
			)
			(layer "F.SilkS")
		)
		(fp_poly
			(pts
				(xy -0.508 0.2794) (xy -0.508 0.2286) (xy -0.635 0.2286) (xy -0.635 -0.254) (xy -0.5334 -0.254)
				(xy -0.5334 -0.2794) (xy 0.5334 -0.2794) (xy 0.5334 -0.254) (xy 0.635 -0.254) (xy 0.635 0.254) (xy 0.5334 0.254)
				(xy 0.5334 0.2794)
			)
			(stroke
				(width 0)
				(type default)
			)
			(fill no)
			(layer "F.CrtYd")
		)
		(pad "1" smd rect
			(at 0.40005 0)
			(size 0.4572 0.508)
			(layers "F.Cu" "F.Mask" "F.Paste")
			(net "GND")
		)
		(pad "2" smd rect
			(at -0.40005 0)
			(size 0.4572 0.508)
			(layers "F.Cu" "F.Mask" "F.Paste")
			(net "VSENSE_P1V05_NODE1_N")
		)
	)
	(footprint ""
		(layer "F.Cu")
		(at 58.53176 -188.126624 90)
		(property "Reference" "C709"
			(at 4.548886 0.346202 90)
			(unlocked yes)
			(layer "F.SilkS")
			(effects
				(font
					(size 0.7874 0.5842)
					(thickness 0.1524)
				)
				(justify left)
			)
		)
		(property "Value" ""
			(at 0 0 90)
			(layer "F.Fab")
			(effects
				(font
					(size 1.27 1.27)
				)
			)
		)
		(duplicate_pad_numbers_are_jumpers no)
		(fp_line
			(start 0.7874 -0.4064)
			(end 0.7874 0.4064)
			(stroke
				(width 0.1524)
				(type default)
			)
			(layer "F.SilkS")
		)
		(fp_line
			(start -0.7874 -0.4064)
			(end 0.7874 -0.4064)
			(stroke
				(width 0.1524)
				(type default)
			)
			(layer "F.SilkS")
		)
		(fp_line
			(start 0 0.381)
			(end 0 -0.381)
			(stroke
				(width 0.1524)
				(type default)
			)
			(layer "F.SilkS")
		)
		(fp_line
			(start 0.7874 0.4064)
			(end -0.7874 0.4064)
			(stroke
				(width 0.1524)
				(type default)
			)
			(layer "F.SilkS")
		)
		(fp_line
			(start -0.7874 0.4064)
			(end -0.7874 -0.4064)
			(stroke
				(width 0.1524)
				(type default)
			)
			(layer "F.SilkS")
		)
		(fp_poly
			(pts
				(xy -0.5334 0.254) (xy -0.635 0.254) (xy -0.635 0.2286) (xy -0.635 -0.254) (xy -0.5334 -0.254) (xy -0.5334 -0.2794)
				(xy 0.5334 -0.2794) (xy 0.5334 -0.254) (xy 0.635 -0.254) (xy 0.635 0.254) (xy 0.5334 0.254) (xy 0.5334 0.2794)
				(xy -0.508 0.2794) (xy -0.5334 0.2794)
			)
			(stroke
				(width 0)
				(type default)
			)
			(fill no)
			(layer "F.CrtYd")
		)
		(pad "1" smd rect
			(at 0.40005 0 90)
			(size 0.4572 0.508)
			(layers "F.Cu" "F.Mask" "F.Paste")
			(net "UART_T2_NODE3_TXD_R")
		)
		(pad "2" smd rect
			(at -0.40005 0 90)
			(size 0.4572 0.508)
			(layers "F.Cu" "F.Mask" "F.Paste")
			(net "GND")
		)
	)
	(footprint ""
		(layer "F.Cu")
		(at 139.93876 -188.126624 90)
		(property "Reference" "C639"
			(at 5.519674 -0.323088 90)
			(unlocked yes)
			(layer "F.SilkS")
			(effects
				(font
					(size 0.7874 0.5842)
					(thickness 0.1524)
				)
				(justify left)
			)
		)
		(property "Value" ""
			(at 0 0 90)
			(layer "F.Fab")
			(effects
				(font
					(size 1.27 1.27)
				)
			)
		)
		(duplicate_pad_numbers_are_jumpers no)
		(fp_line
			(start 0.7874 -0.4064)
			(end 0.7874 0.4064)
			(stroke
				(width 0.1524)
				(type default)
			)
			(layer "F.SilkS")
		)
		(fp_line
			(start -0.7874 -0.4064)
			(end 0.7874 -0.4064)
			(stroke
				(width 0.1524)
				(type default)
			)
			(layer "F.SilkS")
		)
		(fp_line
			(start 0 0.381)
			(end 0 -0.381)
			(stroke
				(width 0.1524)
				(type default)
			)
			(layer "F.SilkS")
		)
		(fp_line
			(start 0.7874 0.4064)
			(end -0.7874 0.4064)
			(stroke
				(width 0.1524)
				(type default)
			)
			(layer "F.SilkS")
		)
		(fp_line
			(start -0.7874 0.4064)
			(end -0.7874 -0.4064)
			(stroke
				(width 0.1524)
				(type default)
			)
			(layer "F.SilkS")
		)
		(fp_poly
			(pts
				(xy -0.5334 0.254) (xy -0.635 0.254) (xy -0.635 0.2286) (xy -0.635 -0.254) (xy -0.5334 -0.254) (xy -0.5334 -0.2794)
				(xy 0.5334 -0.2794) (xy 0.5334 -0.254) (xy 0.635 -0.254) (xy 0.635 0.254) (xy 0.5334 0.254) (xy 0.5334 0.2794)
				(xy -0.508 0.2794) (xy -0.5334 0.2794)
			)
			(stroke
				(width 0)
				(type default)
			)
			(fill no)
			(layer "F.CrtYd")
		)
		(pad "1" smd rect
			(at 0.40005 0 90)
			(size 0.4572 0.508)
			(layers "F.Cu" "F.Mask" "F.Paste")
			(net "T10_NODE2_EN_R")
		)
		(pad "2" smd rect
			(at -0.40005 0 90)
			(size 0.4572 0.508)
			(layers "F.Cu" "F.Mask" "F.Paste")
			(net "GND")
		)
	)
)
